# T6G (Grand Teton) — schematic netlist excerpt (pin names and nets, part order shuffled) for the footprints in the layout excerpt that follows; sources: Cadence DE-HDL packaged netlist, KiCad conversion of 04192023_DAF0TMB3IC0_F0TG_MB_C_brd_V02_OCP.brd

C719  Q_CAP_DIFFBUS  DIFF BUS_0.22UF 6.3V 20% X6S  pkg C0201  page 66 : \1\ = P5E_CPU1_P1_TX_C_DP<11> ; \2\ = P5E_CPU1_P1_TX_DP<11>
C7036  Q_CAP  47UF 4V 20% X6S  pkg C0805  page 279 : A = P0V9_CPU0_RT_2D ; B = GND

X8002  TP_TDR_4P_FTS  TP_TDR_4P_DIP EMPTY  pkg TH  page 260
  S1  = TDR_DIFF_85_IN1_DP
  P1  = T1_GND
  P2  = T1_GND
  S2  = TDR_DIFF_85_IN1_DN

(kicad_pcb
	(version 20260206)
	(generator "pcbnew")
	(generator_version "10.0")
	(general
		(thickness 1.6)
		(legacy_teardrops no)
	)
	(paper "A4")
	(title_block
		(title "04192023_DAF0TMB3IC0_F0TG_MB_C_brd_V02_OCP.brd")
		(comment 1 "Grand Teton / footprints 2353-2355 of 8354")
	)
	(layers
		(0 "F.Cu" signal "TOP")
		(4 "In1.Cu" signal "GND")
		(6 "In2.Cu" signal "IN1")
		(8 "In3.Cu" signal "GND1")
		(10 "In4.Cu" signal "IN2")
		(12 "In5.Cu" signal "GND2")
		(14 "In6.Cu" signal "IN3")
		(16 "In7.Cu" signal "GND3")
		(18 "In8.Cu" signal "VCC")
		(20 "In9.Cu" signal "VCC1")
		(22 "In10.Cu" signal "GND4")
		(24 "In11.Cu" signal "IN4")
		(26 "In12.Cu" signal "GND5")
		(28 "In13.Cu" signal "IN5")
		(30 "In14.Cu" signal "GND6")
		(32 "In15.Cu" signal "IN6")
		(34 "In16.Cu" signal "GND7")
		(2 "B.Cu" signal "BOTTOM")
		(9 "F.Adhes" user "F.Adhesive")
		(11 "B.Adhes" user "B.Adhesive")
		(13 "F.Paste" user "Package Geometry/Pastemask Top")
		(15 "B.Paste" user "Package Geometry/Pastemask Bottom")
		(5 "F.SilkS" user "Ref Des/Silkscreen Top")
		(7 "B.SilkS" user "Ref Des/Silkscreen Bottom")
		(1 "F.Mask" user "Board Geometry/Soldermask Top")
		(3 "B.Mask" user "Board Geometry/Soldermask Bottom")
		(17 "Dwgs.User" user "User.Drawings")
		(19 "Cmts.User" user "User.Comments")
		(21 "Eco1.User" user "User.Eco1")
		(23 "Eco2.User" user "User.Eco2")
		(25 "Edge.Cuts" user "Board Geometry/Outline")
		(27 "Margin" user)
		(31 "F.CrtYd" user "Package Geometry/Place Bound Top")
		(29 "B.CrtYd" user "Package Geometry/Place Bound Bottom")
		(35 "F.Fab" user "Ref Des/Assembly Top")
		(33 "B.Fab" user "Ref Des/Assembly Bottom")
	)
	(footprint ""
		(layer "F.Cu")
		(at 511.924808 7.571994 -90)
		(property "Reference" "X8002"
			(at -1.835658 4.818888 0)
			(unlocked yes)
			(layer "F.SilkS")
			(effects
				(font
					(size 0.7874 0.5842)
					(thickness 0.1524)
				)
				(justify left)
			)
		)
		(property "Value" ""
			(at 0 0 270)
			(layer "F.Fab")
			(effects
				(font
					(size 1.27 1.27)
				)
			)
		)
		(property "Device Type" "TP_TDR_4P_FTS_TH-TP_TDR_4P_DIP,EMPTY,TP15"
			(at 1.30175 1.27 0)
			(unlocked yes)
			(layer "F.Fab")
			(hide yes)
			(effects
				(font
					(size 0.635 0.4064)
					(thickness 0.1524)
				)
			)
		)
		(property "User Part Number" "N_A"
			(at 1.30175 1.27 0)
			(unlocked yes)
			(layer "Cmts.User")
			(hide yes)
			(effects
				(font
					(size 0.635 0.4064)
					(thickness 0.1524)
				)
			)
		)
		(duplicate_pad_numbers_are_jumpers no)
		(fp_line
			(start 0 3.81)
			(end 2.54 3.81)
			(stroke
				(width 0.1524)
				(type default)
			)
			(layer "F.SilkS")
		)
		(fp_line
			(start 2.54 3.81)
			(end 2.54 3.6703)
			(stroke
				(width 0.1524)
				(type default)
			)
			(layer "F.SilkS")
		)
		(fp_line
			(start 0 3.175)
			(end 0 3.81)
			(stroke
				(width 0.1524)
				(type default)
			)
			(layer "F.SilkS")
		)
		(fp_line
			(start 2.54 1.4097)
			(end 2.54 1.1303)
			(stroke
				(width 0.1524)
				(type default)
			)
			(layer "F.SilkS")
		)
		(fp_line
			(start 0 0.635)
			(end 0 1.905)
			(stroke
				(width 0.1524)
				(type default)
			)
			(layer "F.SilkS")
		)
		(fp_line
			(start 2.54 -1.1303)
			(end 2.54 -1.27)
			(stroke
				(width 0.1524)
				(type default)
			)
			(layer "F.SilkS")
		)
		(fp_line
			(start 0 -1.27)
			(end 0 -0.635)
			(stroke
				(width 0.1524)
				(type default)
			)
			(layer "F.SilkS")
		)
		(fp_line
			(start 2.54 -1.27)
			(end 0 -1.27)
			(stroke
				(width 0.1524)
				(type default)
			)
			(layer "F.SilkS")
		)
		(fp_poly
			(pts
				(xy -2.285746 -0.762) (xy -0.761746 0) (xy -2.285746 0.762)
			)
			(stroke
				(width 0)
				(type default)
			)
			(fill yes)
			(layer "F.SilkS")
		)
		(fp_line
			(start 0 3.81)
			(end 2.54 3.81)
			(stroke
				(width 0.1)
				(type default)
			)
			(layer "F.Fab")
		)
		(fp_line
			(start 2.54 3.81)
			(end 2.54 -1.27)
			(stroke
				(width 0.1)
				(type default)
			)
			(layer "F.Fab")
		)
		(fp_line
			(start 0 -1.27)
			(end 0 3.81)
			(stroke
				(width 0.1)
				(type default)
			)
			(layer "F.Fab")
		)
		(fp_line
			(start 2.54 -1.27)
			(end 0 -1.27)
			(stroke
				(width 0.1)
				(type default)
			)
			(layer "F.Fab")
		)
		(fp_poly
			(pts
				(xy -0.761746 0) (xy -2.285746 -0.762) (xy -2.285746 0.762)
			)
			(stroke
				(width 0)
				(type default)
			)
			(fill yes)
			(layer "F.Fab")
		)
		(pad "1" thru_hole circle
			(at 0 0 270)
			(size 1.0033 1.0033)
			(drill 0.249936)
			(layers "*.Cu" "*.Mask")
			(remove_unused_layers no)
			(net "TDR_DIFF_85_IN1_DP")
			(clearance 0.10795)
			(thermal_gap 0.10795)
			(padstack
				(mode front_inner_back)
				(layer "Inner"
					(shape circle)
					(size 0.8001 0.8001)
					(clearance 0.1524)
				)
				(layer "B.Cu"
					(shape circle)
					(size 1.0033 1.0033)
					(clearance 0.10795)
				)
			)
		)
		(pad "2" thru_hole circle
			(at 2.54 0 270)
			(size 1.9939 1.9939)
			(drill 0.249936)
			(layers "*.Cu" "*.Mask")
			(remove_unused_layers no)
			(net "T1_GND")
			(clearance 0.10795)
			(thermal_gap 0.10795)
			(padstack
				(mode front_inner_back)
				(layer "Inner"
					(shape circle)
					(size 0.8001 0.8001)
					(clearance 0.1524)
				)
				(layer "B.Cu"
					(shape circle)
					(size 1.9939 1.9939)
					(clearance 0.10795)
				)
			)
		)
		(pad "3" thru_hole circle
			(at 2.54 2.54 270)
			(size 1.9939 1.9939)
			(drill 0.249936)
			(layers "*.Cu" "*.Mask")
			(remove_unused_layers no)
			(net "T1_GND")
			(clearance 0.10795)
			(thermal_gap 0.10795)
			(padstack
				(mode front_inner_back)
				(layer "Inner"
					(shape circle)
					(size 0.8001 0.8001)
					(clearance 0.1524)
				)
				(layer "B.Cu"
					(shape circle)
					(size 1.9939 1.9939)
					(clearance 0.10795)
				)
			)
		)
		(pad "4" thru_hole circle
			(at 0 2.54 270)
			(size 1.0033 1.0033)
			(drill 0.249936)
			(layers "*.Cu" "*.Mask")
			(remove_unused_layers no)
			(net "TDR_DIFF_85_IN1_DN")
			(clearance 0.10795)
			(thermal_gap 0.10795)
			(padstack
				(mode front_inner_back)
				(layer "Inner"
					(shape circle)
					(size 0.8001 0.8001)
					(clearance 0.1524)
				)
				(layer "B.Cu"
					(shape circle)
					(size 1.0033 1.0033)
					(clearance 0.10795)
				)
			)
		)
	)
	(footprint ""
		(layer "F.Cu")
		(at 398.012412 -410.175456 90)
		(property "Reference" "C7036"
			(at 0 0 90)
			(layer "F.SilkS")
			(hide yes)
			(effects
				(font
					(size 1.27 1.27)
				)
			)
		)
		(property "Value" ""
			(at 0 0 90)
			(layer "F.Fab")
			(effects
				(font
					(size 1.27 1.27)
				)
			)
		)
		(duplicate_pad_numbers_are_jumpers no)
		(fp_line
			(start 1.524 -0.762)
			(end 1.524 0.762)
			(stroke
				(width 0.1524)
				(type default)
			)
			(layer "F.SilkS")
		)
		(fp_line
			(start -1.524 -0.762)
			(end 1.524 -0.762)
			(stroke
				(width 0.1524)
				(type default)
			)
			(layer "F.SilkS")
		)
		(fp_line
			(start 1.524 0.762)
			(end -1.524 0.762)
			(stroke
				(width 0.1524)
				(type default)
			)
			(layer "F.SilkS")
		)
		(fp_line
			(start -1.524 0.762)
			(end -1.524 -0.762)
			(stroke
				(width 0.1524)
				(type default)
			)
			(layer "F.SilkS")
		)
		(fp_line
			(start 1.1049 -0.724916)
			(end -1.1049 -0.724916)
			(stroke
				(width 0.1)
				(type default)
			)
			(layer "F.Fab")
		)
		(fp_line
			(start -1.1049 -0.724916)
			(end -1.1049 0.724916)
			(stroke
				(width 0.1)
				(type default)
			)
			(layer "F.Fab")
		)
		(fp_line
			(start 1.1049 0.724916)
			(end 1.1049 -0.724916)
			(stroke
				(width 0.1)
				(type default)
			)
			(layer "F.Fab")
		)
		(fp_line
			(start -1.1049 0.724916)
			(end 1.1049 0.724916)
			(stroke
				(width 0.1)
				(type default)
			)
			(layer "F.Fab")
		)
		(pad "1" smd rect
			(at -0.889 0 270)
			(size 1.016 1.27)
			(layers "F.Cu" "F.Mask" "F.Paste")
			(net "P0V9_CPU0_RT_2D")
		)
		(pad "2" smd rect
			(at 0.889 0 270)
			(size 1.016 1.27)
			(layers "F.Cu" "F.Mask" "F.Paste")
			(net "GND")
		)
	)
	(footprint ""
		(layer "F.Cu")
		(at 95.939102 -373.03583 -90)
		(property "Reference" "C719"
			(at 0 0 270)
			(layer "F.SilkS")
			(hide yes)
			(effects
				(font
					(size 1.27 1.27)
				)
			)
		)
		(property "Value" ""
			(at 0 0 270)
			(layer "F.Fab")
			(effects
				(font
					(size 1.27 1.27)
				)
			)
		)
		(duplicate_pad_numbers_are_jumpers no)
		(fp_line
			(start -0.299974 0.150114)
			(end -0.299974 -0.150114)
			(stroke
				(width 0.1)
				(type default)
			)
			(layer "F.Fab")
		)
		(fp_line
			(start 0.299974 0.150114)
			(end -0.299974 0.150114)
			(stroke
				(width 0.1)
				(type default)
			)
			(layer "F.Fab")
		)
		(fp_line
			(start -0.299974 -0.150114)
			(end 0.299974 -0.150114)
			(stroke
				(width 0.1)
				(type default)
			)
			(layer "F.Fab")
		)
		(fp_line
			(start 0.299974 -0.150114)
			(end 0.299974 0.150114)
			(stroke
				(width 0.1)
				(type default)
			)
			(layer "F.Fab")
		)
		(pad "1" smd rect
			(at -0.2667 0 270)
			(size 0.3048 0.381)
			(layers "F.Cu" "F.Mask" "F.Paste")
			(net "P5E_CPU1_P1_TX_C_DP<11>")
		)
		(pad "2" smd rect
			(at 0.2667 0 270)
			(size 0.3048 0.381)
			(layers "F.Cu" "F.Mask" "F.Paste")
			(net "P5E_CPU1_P1_TX_DP<11>")
		)
	)
)
